  
Open CloudServer  
network mezzanine I/O 
specification 
V1.1 
 
Authors: 
Mark Shaw, Director of Hardware Engineering, Microsoft 
Martin Goldstein, Principal Systems Architect, Microsoft  


 
2 January 28, 2014 
1 Revision History 
 
Date Name Description 
1/28/2014  Version 1.0 
6/5/2014 MASHAW Version 1.1  
  Section 4, Figure 1 – Updated for NCSI Support 
  Section 5 – Added 40GbE Future Support 
  Section 5.1, Table 1 – Added 40GbE Future Support 
  Section 5.3, Table 3 – Adjusted signals to 
represent dual 10GbE configuration 
  Section 5.3, 5.4 – Added NCSI Support 
  Section 5.4, Table 4 – Fixed pinout.  Swapped 
location of NWK1/NW2 I2C and Present signals. 
  Section 5.5 – Added trace length budgets 
   
   
 
  



Open Compute Project  Open CloudServer network mezzanine I/O specification 
http://opencompute.org 3 
© 2014 Microsoft Corporation. 
 
As of January 28, 2014, the following persons or entities have made this 
Specification available under the Open Web Foundation Final Specification 
Agreement (OWFa 1.0), which is available at 
http://www.openwebfoundation.org/legal/the-owf-1-0-agreements/owfa-1-0 
Microsoft Corporation.  
You can review the signed copies of the Open Web Foundation Agreement Version 
1.0 for this Specification at http://opencompute.org/licensing/, which may also 
include additional parties to those listed above. 
Your use of this Specification may be subject to other third party rights. THIS 
SPECIFICATION IS PROVIDED "AS IS." The contributors expressly disclaim any 
warranties (express, implied, or otherwise), including implied warranties of 
merchantability, noninfringement, fitness for a particular purpose, or title, 
related to the Specification. The entire risk as to implementing or otherwise 
using the Specification is assumed by the Specification implementer and user. 
IN NO EVENT WILL ANY PARTY BE LIABLE TO ANY OTHER PARTY FOR LOST PROFITS OR ANY 
FORM OF INDIRECT, SPECIAL, INCIDENTAL, OR CONSEQUENTIAL DAMAGES OF ANY 
CHARACTER FROM ANY CAUSES OF ACTION OF ANY KIND WITH RESPECT TO THIS 
SPECIFICATION OR ITS GOVERNING AGREEMENT, WHETHER BASED ON BREACH OF CONTRACT, 
TORT (INCLUDING NEGLIGENCE), OR OTHERWISE, AND WHETHER OR NOT THE OTHER PARTY 
HAS BEEN ADVISED OF THE POSSIBILITY OF SUCH DAMAGE. 
CONTRIBUTORS AND LICENSORS OF THIS SPECIFICATION MAY HAVE MENTIONED CERTAIN 
TECHNOLOGIES THAT ARE MERELY REFERENCED WITHIN THIS SPECIFICATION AND NOT 
LICENSED UNDER THE OWF CLA OR OWFa. THE FOLLOWING IS A LIST OF MERELY 
REFERENCED TECHNOLOGY: INTELLIGENT PLATFORM MANAGEMENT INTERFACE (IPMI), I2C 
TRADEMARK OF PHILLIPS SEMICONDUCTOR. IMPLEMENTATION OF THESE TECHNOLOGIES MAY 
BE SUBJECT TO THEIR OWN LEGAL TERMS.  



 
4 January 28, 2014 
2 Scope 
This document focuses on the Open CloudServer system network 
mezzanine input/output (I/O). 
3 Contents 
1 Revision History ......................................................................................................................... 2 
2 Scope ......................................................................................................................................... 4 
3 Contents .................................................................................................................................... 4 
4 Overview.................................................................................................................................... 5 
5 Signaling Interface ..................................................................................................................... 5 
5.1 Ethernet Port Mapping ................................................................................................. 6 
5.2 Connectors ................................................................................................................... 6 
5.3 Signal Definitions .......................................................................................................... 7 
5.4 Connector Pinout ......................................................................................................... 9 
5.5 Electrical Budget ......................................................................................................... 10 
6 Mechanical .............................................................................................................................. 11 
7 Thermal ................................................................................................................................... 12 
8 Appendix: Commonly Used Acronyms .................................................................................... 13 
 
  



Open Compute Project  Open CloudServer network mezzanine I/O specification 
http://opencompute.org 5 
4 Overview 
This document outlines specifications for the Open CloudServer 
mezzanine network interface card (NIC). The NIC interfaces to the 
processor via PCI-Express (PCIe) Gen3 x8 I/O bus and dual 10 Gbit 
Ethernet. Single and dual 10 Gbit Ethernet are supported. NCSI 
and Dual 40 Gbit Ethernet pins have been defined for potential 
future use. 
Figure 1 shows a block diagram of the network mezzanine I/O for a 
2 x 10GbE configuration. 
Blade Motherboard
  
 NIC Mezzanine
Airmax
VS2     NWK2
   Controller
     10GbE
10GbE Port
10GbE Port
NWK2
NWK1
L0
L0
L1
L2
L3
     NWK1
   Controller
     10GbE
L2
L3
L1
L0
L0 L0
L0
L1
L2
L3
NWK1
PCIe
CPU
PCIe PCIe
NCSI
NWK2
BMCNCSI NCSI
Retimer
SEAM SEAF
 
Figure 1. Network Mezzanine I/O connectivity 
 The compute blade uses the following retimer: 
o 4-channel: TI DS110RT410; 7x7mm 48-pin quad-flat no-leads 
(QFN) package 
 NWK2 is reserved for optional future 40GbE 
5 Signaling Interface 
The networking mezzanine interface has been defined to provide 
high bandwidth and a flexible interface. The card receives a PCI-
Express Gen3 x8 bus from the CPU. 
The supported output networks configurations include: 
 1 x 10G Ethernet 
 2 x 10G Ethernet 
 1 x 10G and 1 x 40G Ethernet – Future Support 



 
6 January 28, 2014 
5.1 Ethernet Port Mapping 
Table 1 shows the mappings of the networking signals to the 
backplane. 
Table 1. Network Mezzanine Port to Connector Mapping 
Networking signals 10G blade signal names Description 
NWK_1_TX/RX[0] ENET10G_1_TD/RD 10Gb Ethernet Port 
NWK_2_TX/RX[0] ENET10G_2_TD/RD 10Gb Ethernet Port 
NWK_2_TX/RX[1:3] RSVD 
Can be combined with 
NWK_2_TX/RX0 for 40GbE 
support 
5.2 Connectors 
Table 2 shows the connector part numbers for the network 
mezzanine card. 
Table 2. Connector Part Numbers, Network Mezzanine Card 
Manufacturer Card connector MPN Motherboard connector 
MPN 
Samtec SEAM-20-03.5-L-08-2-A-K-
TR 
SEAF-20-06.5-L-08-2-A-K-
TR 
Molex 45970-2385 45971-2385 
The stackup height of the SEAM is 10mm with a 6.5mm SEAF and a 
3.5mm SEAM connector. In this configuration, it is expected that 
taller components will be place on the top side of the printed 
circuit board (PCB), as shown in Figure 2. 



Open Compute Project  Open CloudServer network mezzanine I/O specification 
http://opencompute.org 7 
SEAF6.5mm
3.5mm
10mm
Device
Heatsink
Backside Keepout
SEAM
 
Figure 2. Connector stackup 
5.3 Signal Definitions 
Table 3 defines the signals used in the NIC mezzanine interface 
for the dual 10GbE configuration. 
Table 3. NIC Mezzanine Connector Signal Definitions 
Bus type I/O Logic Definition 
P3E_CPU1_LAN_RX_DP/N[7:0] O CML PCIe Gen3 from the NIC Mezz to the CPU 
P3E_CPU1_LAN_TX_DP/N[7:0] I CML PCIe Gen3 from the CPU to the NIC Mezz 
CLK_100M_NIC_PE_DP/N I CML 100MHz PCIe Clock 
PCIE_RESET_N I 3.3V PCIe Reset 
MEZZ_PRESENT_N O 3.3V Mezz Present – Should be GND on 
Mezzanine 
NWK_1_TX[0]P/N O CML Port 1 10GbE Transmit from Mezz to 
Motherboard 
NWK_1_RX[0]P/N I CML Port 1 10GbE Receive from Motherboard 
to Mezz 
NWK_2_TX[0]P/N O CML Port 2 10GbE Transmit from Mezz to 
Motherboard 
NWK_2_RX[0]P/N I CML Port 2 10GbE Receive from Motherboard 
to Mezz 
NCSI_TXD[1:0] O LVTTL NCSI Transmit Data[1:0 from NIC to BMC 
NCSI_RXD[1:0] I LVTTL NCSI Receive Data[1:0] from BMC to NIC 
NCSI_TX_EN O LVTTL NCSI Transmit Data Valid from BMC to 
NIC 



 
8 January 28, 2014 
Bus type I/O Logic Definition 
NCSI_CLK_IN I LVTTL NCSI Input Clock 
NCSI_CRS_DV I LVTTL NCSI Receive Data Valid.  Connects to 
Management Controller Transmit Enable 
NCSI_RX_ER I LVTTL NCSI Receive Error 
NWK1_ACT_LED O 3.3V Port 1 Activity LED 
NWK1_LINK_LED O 3.3V Port 1 Link LED 
NWK2_ACT_LED O 3.3V Port 2 Activity LED 
NWK2_LINK_LED O 3.3V Port 2 Link LED 
SMB_ALERT_N O 3.3V I2C Alert from NIC Mezz to BMC 
NWK1_PRESENT_N I 3.3V Port 1 Cable Present Indicator 
NWK1_I2C_SDA I/O 3.3V Port1 I2C Data to Cable 
NWK1_I2C_CLK O 3.3V Port 1 I2C Clock to Cable 
NWK2_PRESENT_N I 3.3V Port 2 Cable Present Indicator 
NWK2_I2C_SDA I/O 3.3V Port 2 I2C Data to Cable 
NWK2_I2C_SCL O 3.3V I2C to QSFP+ Cable 
PCIE_WAKE_N O 3.3V PCIe Wake 
SMB_SCL I 3.3V I2C to BMC 
SMB_SDA I/O 3.3V I2C to BMC 
NIC_MEZZ_ID[1:0] O 3.3V 
NIC Mezz ID – Connected to BMC on 
motherboard 
NIC_MEZZ_ID[1:0] definition is: TBD 
P3V3 I 3.3V 3.3V Input Power 
P3V3_AUX I 3.3V 3.3V Aux Input Power 
P12V_AUX I 12V 12V Input Power 
Ground   Ground Pins 



Open Compute Project  Open CloudServer network mezzanine I/O specification 
http://opencompute.org 9 
5.4 Connector Pinout 
Table 4 lists the pinout for the 160-pin connector on the tray 
mezzanine card that interfaces to the tray backplane. 
Table 4. NIC Mezzanine Connector PinoutPower 
 
 
Table 5 specifies the local area network (LAN) mezzanine power 
ratings for the rail. 
Table 5. LAN Mezzanine Power Ratings 
Power 
rails 
Amps/pin 
(at 40oC) 
Total 
number of 
pins 
Power load 
capacity by 
connector pins 
(W) 
Motherboard 
limited power 
budget (W) 
12V_AUX 2A 2 43.2W 25.2W 
3.3V_AUX 2A 2 11.88W 1.2375W 
3.3V 2A 3 17.82W 9.9W 
Total power budget (per mezzanine card) 25W 
1 GND PCIE_RESET_N GND PCIE_WAKE_N NIC_MEZZ_ID0 SMB_ALERT_N GND CLK_100M_NIC_PE_DP 8
9 P3E_CPU1_LAN_TX_DP<0> GND P3E_CPU1_LAN_RX_DP<7> GND SMB_SCL NWK2_PRESENT_N GND CLK_100M_NIC_PE_DN 16
17 P3E_CPU1_LAN_TX_DN<0> GND P3E_CPU1_LAN_RX_DN<7> GND SMB_SDA GND MEZZ_PRESENT_N GND 24
25 GND P3E_CPU1_LAN_TX_DP<1> GND P3E_CPU1_LAN_RX_DP<6> GND NCSI_TXD_0 GND NWK_2_TX0P 32
33 GND P3E_CPU1_LAN_TX_DN<1> GND P3E_CPU1_LAN_RX_DN<6> GND NCSI_TXD_1 GND NWK_2_TX0N 40
41 P3E_CPU1_LAN_TX_DP<2> GND P3E_CPU1_LAN_RX_DP<5> GND NCSI_RXD_0 GND NWK_2_TX1P GND 48
49 P3E_CPU1_LAN_TX_DN<2> GND P3E_CPU1_LAN_RX_DN<5> GND NCSI_RXD_1 GND NWK_2_TX1N GND 56
57 GND P3E_CPU1_LAN_TX_DP<3> GND P3E_CPU1_LAN_RX_DP<4> GND NCSI_TX_EN GND NWK_2_TX2P 64
65 GND P3E_CPU1_LAN_TX_DN<3> GND P3E_CPU1_LAN_RX_DN<4> GND NCSI_CLK_IN GND NWK_2_TX2N 72
73 P3E_CPU1_LAN_TX_DP<4> GND P3E_CPU1_LAN_RX_DP<0> GND NCSI_CRS_DV GND NWK_2_TX3P GND 80
81 P3E_CPU1_LAN_TX_DN<4> GND P3E_CPU1_LAN_RX_DN<0> GND NCSI_RX_ER GND NWK_2_TX3N GND 88
89 GND P3E_CPU1_LAN_TX_DP<5> GND P3E_CPU1_LAN_RX_DP<1> GND NWK_1_ACT_LED GND NWK_2_RX0P 96
97 GND P3E_CPU1_LAN_TX_DN<5> GND P3E_CPU1_LAN_RX_DN<1> GND NWK_1_LINK_LED GND NWK_2_RX0N 104
105 P3E_CPU1_LAN_TX_DP<6> GND P3E_CPU1_LAN_RX_DP<2> GND NWK_2_ACT_LED GND NWK_2_RX1N GND 112
113 P3E_CPU1_LAN_TX_DN<6> GND P3E_CPU1_LAN_RX_DN<2> GND NWK_2_LINK_LED GND NWK_2_RX1P GND 120
121 GND P3E_CPU1_LAN_TX_DP<7> GND P3E_CPU1_LAN_RX_DP<3> GND NWK_1_TX0P GND NWK_2_RX2N 128
129 NWK2_I2C_SDA P3E_CPU1_LAN_TX_DN<7> GND P3E_CPU1_LAN_RX_DN<3> GND NWK_1_TX0N GND NWK_2_RX2P 136
137 NWK2_I2C_SCL GND NIC_MEZZ_ID1 GND NWK_1_RX0P GND NWK_2_RX3N GND 144
145 P12V_AUX P3V3_AUX P3V3 GND NWK_1_RX0N GND NWK_2_RX3P NWK1_I2C_SDA 152
153 P12V_AUX P3V3_AUX P3V3 P3V3 GND NWK1_PRESENT_N GND NWK1_I2C_SCL 160



 
10 January 28, 2014 
Figure 3 shows the LAN mezzanine power-up sequence. 
 
Figure 3. LAN mezzanine power-up sequence 
Note that the maximum power consumption of the mezzanine cards is 
25W. The reset signal conforms to the PCI Express reset 
specifications. 
5.5 Electrical Budget 
Table 6 below shows the budgetary trace lengths for critical 
signals in the NIC Mezzanine assuming standard FR-4 PCB material.  
This is intended to communicate the current topology expectation 
for compatibility with the existing design blade motherboard 
design and is not intended to replace simulation.   
 
Table 6. Budgetary Trace Lengths 
 Trace Length 
(NIC Mezz) 
PCIe < 3” 
10GbE < 3” 
NCSI < 3” 
I2C < 3” 
 
 


Open Compute Project  Open CloudServer network mezzanine I/O specification 
http://opencompute.org 11 
Blade Motherboard
  
 NIC Mezzanine
Airmax
VS2     NWK2
   Controller
     10GbE
10GbE Port
10GbE Port
NWK2
NWK1
L0
L0
L1
L2
L3
     NWK1
   Controller
     10GbE
L2
L3
L1
L0
L0 L0
L0
L1
L2
L3
NWK1
PCIe
CPU
PCIe PCIe
NCSI
NWK2
BMCNCSI NCSI
Retimer
SEAM SEAF
< 3" < 3"
 
6 Mechanical 
Figure 4 shows the dimensions of the network mezzanine. Note that 
PCB board thickness can vary as long as the keep-in volumes are 
not violated. 



 
12 January 28, 2014 
 `
  
Figure 4. Network mezzanine dimensions 
7 Thermal 
The network mezzanine cards are designed to be located at the 
extreme downstream position of the server, so the air is heated 
by all of the upstream components before reaching the cards. The 
direction of air flow is shown in Figure 4.   
Table 7 shows the worst-case environmental conditions that can be 
expected at the network mezzanine card inlet. The thermal 
solution and component selection should be sufficient for these 
conditions.  
Table 7. Environmental Operating Conditions, Network Mezzanine Card 
Variable Worst case operating condition 
Approaching airflow rate 200 ft/min, uniform 



Open Compute Project  Open CloudServer network mezzanine I/O specification 
http://opencompute.org 13 
Maximum allowable pressure drop 
across card 
0.040 “H2O max at 200 ft/min 
Approaching airflow temperature 66OC 
8 Appendix: Commonly Used Acronyms 
This section provides definitions of acronyms used in the system 
specifications. 
ACPI – advanced 
configuration and power 
interface  
AHCI – advanced host 
controller interface 
AHJ – authority having 
jurisdiction 
ANSI – American National 
Standards Institute 
API – application 
programming interface 
ASHRAE – American Society 
of Heating, Refrigerating 
and Air Conditioning 
Engineers 
ASIC – application-specific 
integrated circuit 
BCD – binary-coded decimal 
BIOS – basic input/output 
system 
BMC – baseboard management 
controller 
CFM – cubic feet per minute 
(measure of volume flow 
rate) 
CM – Chassis Manager 
CMOS – complementary metal–
oxide–semiconductor 
COLO – co-location 
CTS – clear to send 
DCMI – data center 
manageability interface 
DDR3 – double data rate 
type 3  
DHCP – dynamic host 
configuration protocol 
DIMM – dual inline memory 
module  
DPC - DIMMs per memory 
channel  
DRAM – dynamic random 
access memory 
DSR – data set ready 
DTR – data terminal ready 
ECC – error-correcting code 
EEPROM - electrically 
erasable programmable read-
only memory 
EIA – Electronic Industries 
Alliance 
EMC – electromagnetic 
compatibility 
EMI – electromagnetic 
interference 
FRU – field replaceable 
unit 
FTP – file transfer 
protocol 
GPIO – general purpose 
input output 
GUID – globally unique 
identifier 
HBI – high business 
intelligence 
HCK – Windows Hardware 
Certification Kit 
HMD – hardware monitoring 
device 
HT – hyperthreading 
I2C – inter-integrated 
circuit 
IBC – international 
building code 
IDE – integrated 
development environment 
IEC - International 
Electrotechnical Commission 
IOC – I/O controller 



 
14 January 28, 2014 
IPMI – intelligent platform 
management interface 
IPsec – IP security 
ITPAC – IT pre-assembled 
components 
JBOD – “just a bunch of 
disks” 
KCS – keyboard controller 
style 
L2 – layer 2 
LAN – local area network 
LFF – large form factor 
LPC – low pin count 
LS – least significant 
LUN – logical unit number 
MAC – media access control 
MDC – modular data center 
containers 
MLC – multi-level call 
MTBF – mean time between 
failures  
MUX – multiplexer 
NIC – network interface 
card 
NUMA – non-uniform memory 
access 
OOB – out of band 
OSHA - Occupational Safety 
& Health Administration 
OTS – off the shelf 
PCB – printed circuit board 
PCIe – peripheral component 
interconnect express 
PCH – platform control hub 
PDB – power distribution 
backplane 
PDU – power distribution 
unit 
Ph-ph – phase to phase 
Ph-N – phase to neutral 
PNP – plug and play 
POST – power-on self-test 
PSU – power supply unit 
PWM – pulse-width 
modulation 
PXE – preboot execution 
environment 
QDR – quad data rate 
QFN – quad flat package no-
lead 
QPI – Intel QuickPath 
Interconnect 
QSFP – quad small form-
factor pluggable 
RAID – redundant array of 
independent disks 
REST - representational 
state transfer 
RM – rack manager 
RMA – remote management 
agent 
ROC – RAID-on-chip 
controller 
RSS – receive-side scaling 
RTS – request to send 
RU – rack unit 
RxD – received data 
SAS – serial-attached small 
computer system interface 
(SCSI) 
SATA – serial AT attachment 
SCK – serial clock 
SCSI – small computer 
system interface 
SDA – serial data signal 
SDR – sensor data record 
SFF – small form factor 
SFP – small form-factor 
pluggable  
SMBUS – systems management 
bus 
SMBIOS – systems management 
BIOS 
SOL – serial over LAN 
SPI – serial peripheral 
interface 
SSD – solid-state drive 
TB – tray backplane 
TDP – thermal design power 



Open Compute Project  Open CloudServer network mezzanine I/O specification 
http://opencompute.org 15 
TM – tray midplane 
TOR – top of rack 
TPM – trusted platform 
module 
TxD – transmit data 
U – rack unit 
UART – universal 
asynchronous 
receiver/transmitter 
UEFI – unified extensible 
firmware interface 
UL – Underwriters 
Laboratories 
UPS – uninterrupted power 
supply 
Vpp – voltage peak to peak 
WMI – Windows Management 
Interface 
 